(kicad_pcb
	(version 20260206)
	(generator "pcbnew")
	(generator_version "10.0")
	(general
		(thickness 1.6)
		(legacy_teardrops no)
	)
	(paper "A4")
	(title_block
		(title "01162023_DA0F0TEBIF0_F0T_Expander_BD_F_brd_V02_OCP.brd")
		(comment 1 "Grand Teton / footprints 5012-5016 of 9728")
	)
	(layers
		(0 "F.Cu" signal "TOP")
		(4 "In1.Cu" signal "GND")
		(6 "In2.Cu" signal "VCC")
		(8 "In3.Cu" signal "VCC1")
		(10 "In4.Cu" signal "GND1")
		(12 "In5.Cu" signal "IN1")
		(14 "In6.Cu" signal "GND2")
		(16 "In7.Cu" signal "IN2")
		(18 "In8.Cu" signal "GND3")
		(20 "In9.Cu" signal "IN3")
		(22 "In10.Cu" signal "GND4")
		(24 "In11.Cu" signal "IN4")
		(26 "In12.Cu" signal "GND5")
		(28 "In13.Cu" signal "IN5")
		(30 "In14.Cu" signal "GND6")
		(32 "In15.Cu" signal "IN6")
		(34 "In16.Cu" signal "GND7")
		(2 "B.Cu" signal "BOTTOM")
		(9 "F.Adhes" user "F.Adhesive")
		(11 "B.Adhes" user "B.Adhesive")
		(13 "F.Paste" user "Package Geometry/Pastemask Top")
		(15 "B.Paste" user "Package Geometry/Pastemask Bottom")
		(5 "F.SilkS" user "Ref Des/Silkscreen Top")
		(7 "B.SilkS" user "Ref Des/Silkscreen Bottom")
		(1 "F.Mask" user "Board Geometry/Soldermask Top")
		(3 "B.Mask" user "Board Geometry/Soldermask Bottom")
		(17 "Dwgs.User" user "User.Drawings")
		(19 "Cmts.User" user "User.Comments")
		(21 "Eco1.User" user "User.Eco1")
		(23 "Eco2.User" user "User.Eco2")
		(25 "Edge.Cuts" user "Board Geometry/Outline")
		(27 "Margin" user)
		(31 "F.CrtYd" user "Package Geometry/Place Bound Top")
		(29 "B.CrtYd" user "Package Geometry/Place Bound Bottom")
		(35 "F.Fab" user "Ref Des/Assembly Top")
		(33 "B.Fab" user "Ref Des/Assembly Bottom")
	)
	(footprint ""
		(layer "F.Cu")
		(at 198.815198 -59.546236 90)
		(property "Reference" "C2891"
			(at 0 0 90)
			(layer "F.SilkS")
			(hide yes)
			(effects
				(font
					(size 1.27 1.27)
				)
			)
		)
		(property "Value" ""
			(at 0 0 90)
			(layer "F.Fab")
			(effects
				(font
					(size 1.27 1.27)
				)
			)
		)
		(duplicate_pad_numbers_are_jumpers no)
		(fp_line
			(start 0.7874 -0.4064)
			(end 0.7874 0.4064)
			(stroke
				(width 0.1524)
				(type default)
			)
			(layer "F.SilkS")
		)
		(fp_line
			(start -0.7874 -0.4064)
			(end 0.7874 -0.4064)
			(stroke
				(width 0.1524)
				(type default)
			)
			(layer "F.SilkS")
		)
		(fp_line
			(start 0.7874 0.4064)
			(end -0.7874 0.4064)
			(stroke
				(width 0.1524)
				(type default)
			)
			(layer "F.SilkS")
		)
		(fp_line
			(start -0.7874 0.4064)
			(end -0.7874 -0.4064)
			(stroke
				(width 0.1524)
				(type default)
			)
			(layer "F.SilkS")
		)
		(fp_line
			(start -0.12065 -0.305054)
			(end -0.12065 -0.2794)
			(stroke
				(width 0.1)
				(type default)
			)
			(layer "F.Fab")
		)
		(fp_line
			(start -0.67945 -0.305054)
			(end -0.12065 -0.305054)
			(stroke
				(width 0.1)
				(type default)
			)
			(layer "F.Fab")
		)
		(fp_line
			(start 0.67945 -0.3048)
			(end 0.67945 0.3048)
			(stroke
				(width 0.1)
				(type default)
			)
			(layer "F.Fab")
		)
		(fp_line
			(start 0.12065 -0.3048)
			(end 0.67945 -0.3048)
			(stroke
				(width 0.1)
				(type default)
			)
			(layer "F.Fab")
		)
		(fp_line
			(start 0.12065 -0.2794)
			(end 0.12065 -0.3048)
			(stroke
				(width 0.1)
				(type default)
			)
			(layer "F.Fab")
		)
		(fp_line
			(start -0.12065 -0.2794)
			(end 0.12065 -0.2794)
			(stroke
				(width 0.1)
				(type default)
			)
			(layer "F.Fab")
		)
		(fp_line
			(start 0.120396 0.2794)
			(end -0.12065 0.2794)
			(stroke
				(width 0.1)
				(type default)
			)
			(layer "F.Fab")
		)
		(fp_line
			(start -0.12065 0.2794)
			(end -0.12065 0.3048)
			(stroke
				(width 0.1)
				(type default)
			)
			(layer "F.Fab")
		)
		(fp_line
			(start 0.67945 0.3048)
			(end 0.120396 0.3048)
			(stroke
				(width 0.1)
				(type default)
			)
			(layer "F.Fab")
		)
		(fp_line
			(start 0.120396 0.3048)
			(end 0.120396 0.2794)
			(stroke
				(width 0.1)
				(type default)
			)
			(layer "F.Fab")
		)
		(fp_line
			(start -0.12065 0.3048)
			(end -0.67945 0.3048)
			(stroke
				(width 0.1)
				(type default)
			)
			(layer "F.Fab")
		)
		(fp_line
			(start -0.67945 0.3048)
			(end -0.67945 -0.305054)
			(stroke
				(width 0.1)
				(type default)
			)
			(layer "F.Fab")
		)
		(pad "1" smd circle
			(at -0.40005 0 90)
			(size 0 0)
			(layers "F.Cu" "F.Mask" "F.Paste")
			(net "SSD7_AUX_P3V3_EN_R")
		)
		(pad "2" smd circle
			(at 0.40005 0 90)
			(size 0 0)
			(layers "F.Cu" "F.Mask" "F.Paste")
			(net "GND")
		)
	)
	(footprint ""
		(layer "F.Cu")
		(at 459.153768 8.175752 180)
		(property "Reference" "DE15T_1"
			(at 2.766568 3.145282 0)
			(unlocked yes)
			(layer "F.SilkS")
			(effects
				(font
					(size 0.7874 0.5842)
					(thickness 0.1524)
				)
				(justify left)
			)
		)
		(property "Value" ""
			(at 0 0 180)
			(layer "F.Fab")
			(effects
				(font
					(size 1.27 1.27)
				)
			)
		)
		(duplicate_pad_numbers_are_jumpers no)
		(fp_line
			(start 1.2192 2.1082)
			(end -1.2192 2.1082)
			(stroke
				(width 0.1524)
				(type default)
			)
			(layer "F.SilkS")
		)
		(fp_line
			(start 1.2192 -2.1082)
			(end 1.2192 2.1082)
			(stroke
				(width 0.1524)
				(type default)
			)
			(layer "F.SilkS")
		)
		(fp_line
			(start -1.2192 2.1082)
			(end -1.2192 -2.1082)
			(stroke
				(width 0.1524)
				(type default)
			)
			(layer "F.SilkS")
		)
		(fp_line
			(start -1.2192 -2.1082)
			(end 1.2192 -2.1082)
			(stroke
				(width 0.1524)
				(type default)
			)
			(layer "F.SilkS")
		)
		(pad "" np_thru_hole circle
			(at -2.8829 -1.27 90)
			(size 1.0414 1.0414)
			(drill 1.0414)
			(layers "*.Cu" "*.Mask")
			(clearance 0.381)
			(thermal_gap 0.381)
		)
		(pad "" np_thru_hole circle
			(at -2.8829 1.27 90)
			(size 1.0414 1.0414)
			(drill 1.0414)
			(layers "*.Cu" "*.Mask")
			(clearance 0.381)
			(thermal_gap 0.381)
		)
		(pad "" np_thru_hole circle
			(at 3.4671 -1.27 90)
			(size 1.0414 1.0414)
			(drill 1.0414)
			(layers "*.Cu" "*.Mask")
			(clearance 0.381)
			(thermal_gap 0.381)
		)
		(pad "" np_thru_hole circle
			(at 3.4671 1.27 90)
			(size 1.0414 1.0414)
			(drill 1.0414)
			(layers "*.Cu" "*.Mask")
			(clearance 0.381)
			(thermal_gap 0.381)
		)
		(pad "1" smd rect
			(at 0.8255 -0.249936 90)
			(size 0.3048 0.508)
			(layers "F.Cu" "F.Mask" "F.Paste")
			(net "85_10INCH_IN3_DP")
		)
		(pad "2" smd rect
			(at 0.8255 0.249936 90)
			(size 0.3048 0.508)
			(layers "F.Cu" "F.Mask" "F.Paste")
			(net "85_10INCH_IN3_DN")
		)
		(pad "3" smd circle
			(at 0 0 180)
			(size 0 0)
			(layers "F.Cu" "F.Mask" "F.Paste")
			(net "COUPON_GND2")
		)
		(zone
			(layer "F.Cu")
			(hatch none 0.5)
			(connect_pads
				(clearance 0)
			)
			(min_thickness 0.25)
			(keepout
				(tracks not_allowed)
				(vias allowed)
				(pads allowed)
				(copperpour not_allowed)
				(footprints allowed)
			)
			(placement
				(enabled no)
				(sheetname "")
			)
			(fill
				(thermal_gap 0.5)
				(thermal_bridge_width 0.5)
				(island_removal_mode 0)
			)
			(polygon
				(pts
					(xy 458.036168 8.724392) (xy 458.036168 8.628888) (xy 458.633068 8.628888) (xy 458.633068 8.222488)
					(xy 458.036168 8.222488) (xy 458.036168 8.129016) (xy 458.633068 8.129016) (xy 458.633068 7.722616)
					(xy 458.036168 7.722616) (xy 458.036168 7.627112) (xy 458.734668 7.627112) (xy 458.734668 8.724392)
				)
			)
		)
		(zone
			(layers "F.Cu" "B.Cu" "In1.Cu" "In2.Cu" "In3.Cu" "In4.Cu" "In5.Cu" "In6.Cu"
				"In7.Cu" "In8.Cu" "In9.Cu" "In10.Cu" "In11.Cu" "In12.Cu" "In13.Cu" "In14.Cu"
				"In15.Cu" "In16.Cu"
			)
			(hatch none 0.5)
			(connect_pads
				(clearance 0)
			)
			(min_thickness 0.25)
			(keepout
				(tracks not_allowed)
				(vias allowed)
				(pads allowed)
				(copperpour not_allowed)
				(footprints allowed)
			)
			(placement
				(enabled no)
				(sheetname "")
			)
			(fill
				(thermal_gap 0.5)
				(thermal_bridge_width 0.5)
				(island_removal_mode 0)
			)
			(polygon
				(pts
					(arc
						(start 456.613768 6.905752)
						(mid 454.759568 6.905752)
						(end 456.613768 6.905752)
					)
				)
			)
		)
		(zone
			(layers "F.Cu" "B.Cu" "In1.Cu" "In2.Cu" "In3.Cu" "In4.Cu" "In5.Cu" "In6.Cu"
				"In7.Cu" "In8.Cu" "In9.Cu" "In10.Cu" "In11.Cu" "In12.Cu" "In13.Cu" "In14.Cu"
				"In15.Cu" "In16.Cu"
			)
			(hatch none 0.5)
			(connect_pads
				(clearance 0)
			)
			(min_thickness 0.25)
			(keepout
				(tracks not_allowed)
				(vias allowed)
				(pads allowed)
				(copperpour not_allowed)
				(footprints allowed)
			)
			(placement
				(enabled no)
				(sheetname "")
			)
			(fill
				(thermal_gap 0.5)
				(thermal_bridge_width 0.5)
				(island_removal_mode 0)
			)
			(polygon
				(pts
					(arc
						(start 456.613768 9.445752)
						(mid 454.759568 9.445752)
						(end 456.613768 9.445752)
					)
				)
			)
		)
		(zone
			(layers "F.Cu" "B.Cu" "In1.Cu" "In2.Cu" "In3.Cu" "In4.Cu" "In5.Cu" "In6.Cu"
				"In7.Cu" "In8.Cu" "In9.Cu" "In10.Cu" "In11.Cu" "In12.Cu" "In13.Cu" "In14.Cu"
				"In15.Cu" "In16.Cu"
			)
			(hatch none 0.5)
			(connect_pads
				(clearance 0)
			)
			(min_thickness 0.25)
			(keepout
				(tracks not_allowed)
				(vias allowed)
				(pads allowed)
				(copperpour not_allowed)
				(footprints allowed)
			)
			(placement
				(enabled no)
				(sheetname "")
			)
			(fill
				(thermal_gap 0.5)
				(thermal_bridge_width 0.5)
				(island_removal_mode 0)
			)
			(polygon
				(pts
					(arc
						(start 462.963768 6.905752)
						(mid 461.109568 6.905752)
						(end 462.963768 6.905752)
					)
				)
			)
		)
		(zone
			(layers "F.Cu" "B.Cu" "In1.Cu" "In2.Cu" "In3.Cu" "In4.Cu" "In5.Cu" "In6.Cu"
				"In7.Cu" "In8.Cu" "In9.Cu" "In10.Cu" "In11.Cu" "In12.Cu" "In13.Cu" "In14.Cu"
				"In15.Cu" "In16.Cu"
			)
			(hatch none 0.5)
			(connect_pads
				(clearance 0)
			)
			(min_thickness 0.25)
			(keepout
				(tracks not_allowed)
				(vias allowed)
				(pads allowed)
				(copperpour not_allowed)
				(footprints allowed)
			)
			(placement
				(enabled no)
				(sheetname "")
			)
			(fill
				(thermal_gap 0.5)
				(thermal_bridge_width 0.5)
				(island_removal_mode 0)
			)
			(polygon
				(pts
					(arc
						(start 462.963768 9.445752)
						(mid 461.109568 9.445752)
						(end 462.963768 9.445752)
					)
				)
			)
		)
	)
	(footprint ""
		(layer "F.Cu")
		(at 380.711456 -280.443432 -90)
		(property "Reference" "R4596"
			(at 0 0 270)
			(layer "F.SilkS")
			(hide yes)
			(effects
				(font
					(size 1.27 1.27)
				)
			)
		)
		(property "Value" ""
			(at 0 0 270)
			(layer "F.Fab")
			(effects
				(font
					(size 1.27 1.27)
				)
			)
		)
		(duplicate_pad_numbers_are_jumpers no)
		(fp_line
			(start -0.7874 0.4064)
			(end -0.7874 -0.4064)
			(stroke
				(width 0.1524)
				(type default)
			)
			(layer "F.SilkS")
		)
		(fp_line
			(start 0.7874 0.4064)
			(end -0.7874 0.4064)
			(stroke
				(width 0.1524)
				(type default)
			)
			(layer "F.SilkS")
		)
		(fp_line
			(start -0.7874 -0.4064)
			(end 0.7874 -0.4064)
			(stroke
				(width 0.1524)
				(type default)
			)
			(layer "F.SilkS")
		)
		(fp_line
			(start 0.7874 -0.4064)
			(end 0.7874 0.4064)
			(stroke
				(width 0.1524)
				(type default)
			)
			(layer "F.SilkS")
		)
		(fp_line
			(start -0.67945 0.3048)
			(end -0.67945 -0.305054)
			(stroke
				(width 0.1)
				(type default)
			)
			(layer "F.Fab")
		)
		(fp_line
			(start -0.12065 0.3048)
			(end -0.67945 0.3048)
			(stroke
				(width 0.1)
				(type default)
			)
			(layer "F.Fab")
		)
		(fp_line
			(start 0.120396 0.3048)
			(end 0.120396 0.2794)
			(stroke
				(width 0.1)
				(type default)
			)
			(layer "F.Fab")
		)
		(fp_line
			(start 0.67945 0.3048)
			(end 0.120396 0.3048)
			(stroke
				(width 0.1)
				(type default)
			)
			(layer "F.Fab")
		)
		(fp_line
			(start -0.12065 0.2794)
			(end -0.12065 0.3048)
			(stroke
				(width 0.1)
				(type default)
			)
			(layer "F.Fab")
		)
		(fp_line
			(start 0.120396 0.2794)
			(end -0.12065 0.2794)
			(stroke
				(width 0.1)
				(type default)
			)
			(layer "F.Fab")
		)
		(fp_line
			(start -0.12065 -0.2794)
			(end 0.12065 -0.2794)
			(stroke
				(width 0.1)
				(type default)
			)
			(layer "F.Fab")
		)
		(fp_line
			(start 0.12065 -0.2794)
			(end 0.12065 -0.3048)
			(stroke
				(width 0.1)
				(type default)
			)
			(layer "F.Fab")
		)
		(fp_line
			(start 0.12065 -0.3048)
			(end 0.67945 -0.3048)
			(stroke
				(width 0.1)
				(type default)
			)
			(layer "F.Fab")
		)
		(fp_line
			(start 0.67945 -0.3048)
			(end 0.67945 0.3048)
			(stroke
				(width 0.1)
				(type default)
			)
			(layer "F.Fab")
		)
		(fp_line
			(start -0.67945 -0.305054)
			(end -0.12065 -0.305054)
			(stroke
				(width 0.1)
				(type default)
			)
			(layer "F.Fab")
		)
		(fp_line
			(start -0.12065 -0.305054)
			(end -0.12065 -0.2794)
			(stroke
				(width 0.1)
				(type default)
			)
			(layer "F.Fab")
		)
		(pad "1" smd circle
			(at -0.40005 0 270)
			(size 0 0)
			(layers "F.Cu" "F.Mask" "F.Paste")
			(net "SYSPLL_VDDA18_PEX3")
		)
		(pad "2" smd circle
			(at 0.40005 0 270)
			(size 0 0)
			(layers "F.Cu" "F.Mask" "F.Paste")
			(net "SYSPLL_VDDA18_PEX3_R")
		)
	)
	(footprint ""
		(layer "F.Cu")
		(at 361.506262 -134.434326)
		(property "Reference" "PC304"
			(at 0 0 0)
			(layer "F.SilkS")
			(hide yes)
			(effects
				(font
					(size 1.27 1.27)
				)
			)
		)
		(property "Value" ""
			(at 0 0 0)
			(layer "F.Fab")
			(effects
				(font
					(size 1.27 1.27)
				)
			)
		)
		(duplicate_pad_numbers_are_jumpers no)
		(fp_line
			(start -0.7874 -0.4064)
			(end 0.7874 -0.4064)
			(stroke
				(width 0.1524)
				(type default)
			)
			(layer "F.SilkS")
		)
		(fp_line
			(start -0.7874 0.4064)
			(end -0.7874 -0.4064)
			(stroke
				(width 0.1524)
				(type default)
			)
			(layer "F.SilkS")
		)
		(fp_line
			(start 0.7874 -0.4064)
			(end 0.7874 0.4064)
			(stroke
				(width 0.1524)
				(type default)
			)
			(layer "F.SilkS")
		)
		(fp_line
			(start 0.7874 0.4064)
			(end -0.7874 0.4064)
			(stroke
				(width 0.1524)
				(type default)
			)
			(layer "F.SilkS")
		)
		(fp_line
			(start -0.67945 -0.305054)
			(end -0.12065 -0.305054)
			(stroke
				(width 0.1)
				(type default)
			)
			(layer "F.Fab")
		)
		(fp_line
			(start -0.67945 0.3048)
			(end -0.67945 -0.305054)
			(stroke
				(width 0.1)
				(type default)
			)
			(layer "F.Fab")
		)
		(fp_line
			(start -0.12065 -0.305054)
			(end -0.12065 -0.2794)
			(stroke
				(width 0.1)
				(type default)
			)
			(layer "F.Fab")
		)
		(fp_line
			(start -0.12065 -0.2794)
			(end 0.12065 -0.2794)
			(stroke
				(width 0.1)
				(type default)
			)
			(layer "F.Fab")
		)
		(fp_line
			(start -0.12065 0.2794)
			(end -0.12065 0.3048)
			(stroke
				(width 0.1)
				(type default)
			)
			(layer "F.Fab")
		)
		(fp_line
			(start -0.12065 0.3048)
			(end -0.67945 0.3048)
			(stroke
				(width 0.1)
				(type default)
			)
			(layer "F.Fab")
		)
		(fp_line
			(start 0.120396 0.2794)
			(end -0.12065 0.2794)
			(stroke
				(width 0.1)
				(type default)
			)
			(layer "F.Fab")
		)
		(fp_line
			(start 0.120396 0.3048)
			(end 0.120396 0.2794)
			(stroke
				(width 0.1)
				(type default)
			)
			(layer "F.Fab")
		)
		(fp_line
			(start 0.12065 -0.3048)
			(end 0.67945 -0.3048)
			(stroke
				(width 0.1)
				(type default)
			)
			(layer "F.Fab")
		)
		(fp_line
			(start 0.12065 -0.2794)
			(end 0.12065 -0.3048)
			(stroke
				(width 0.1)
				(type default)
			)
			(layer "F.Fab")
		)
		(fp_line
			(start 0.67945 -0.3048)
			(end 0.67945 0.3048)
			(stroke
				(width 0.1)
				(type default)
			)
			(layer "F.Fab")
		)
		(fp_line
			(start 0.67945 0.3048)
			(end 0.120396 0.3048)
			(stroke
				(width 0.1)
				(type default)
			)
			(layer "F.Fab")
		)
		(pad "1" smd circle
			(at -0.40005 0)
			(size 0 0)
			(layers "F.Cu" "F.Mask" "F.Paste")
			(net "P12V_AUX")
		)
		(pad "2" smd circle
			(at 0.40005 0)
			(size 0 0)
			(layers "F.Cu" "F.Mask" "F.Paste")
			(net "GND")
		)
	)
	(footprint ""
		(layer "F.Cu")
		(at 56.034686 -367.627662 180)
		(property "Reference" "C3984"
			(at 0 0 180)
			(layer "F.SilkS")
			(hide yes)
			(effects
				(font
					(size 1.27 1.27)
				)
			)
		)
		(property "Value" ""
			(at 0 0 180)
			(layer "F.Fab")
			(effects
				(font
					(size 1.27 1.27)
				)
			)
		)
		(duplicate_pad_numbers_are_jumpers no)
		(fp_line
			(start 0.299974 0.150114)
			(end -0.299974 0.150114)
			(stroke
				(width 0.1)
				(type default)
			)
			(layer "F.Fab")
		)
		(fp_line
			(start 0.299974 -0.150114)
			(end 0.299974 0.150114)
			(stroke
				(width 0.1)
				(type default)
			)
			(layer "F.Fab")
		)
		(fp_line
			(start -0.299974 0.150114)
			(end -0.299974 -0.150114)
			(stroke
				(width 0.1)
				(type default)
			)
			(layer "F.Fab")
		)
		(fp_line
			(start -0.299974 -0.150114)
			(end 0.299974 -0.150114)
			(stroke
				(width 0.1)
				(type default)
			)
			(layer "F.Fab")
		)
		(pad "1" smd rect
			(at -0.2667 0 180)
			(size 0.3048 0.381)
			(layers "F.Cu" "F.Mask" "F.Paste")
			(net "P4E_PEX0_STN3_TX_DP<49>")
		)
		(pad "2" smd rect
			(at 0.2667 0 180)
			(size 0.3048 0.381)
			(layers "F.Cu" "F.Mask" "F.Paste")
			(net "P4E_PEX0_STN3_TX_C_DP<49>")
		)
	)
)
